(kicad_pcb
	(version 20241229)
	(generator "pcbnew")
	(generator_version "9.0")
	(general
		(thickness 1.599998)
		(legacy_teardrops no)
	)
	(paper "A4")
	(title_block
		(title "Artix - Datacenter Secure Control Module (DC-SCM)")
		(date "2024-11-06")
		(rev "1.1.3")
		(comment 9 "footprint 214 of 544 (J9), pads 1-91 of 168")
	)
	(layers
		(0 "F.Cu" signal)
		(4 "In1.Cu" signal)
		(6 "In2.Cu" signal)
		(8 "In3.Cu" signal)
		(10 "In4.Cu" signal)
		(12 "In5.Cu" signal)
		(14 "In6.Cu" signal)
		(2 "B.Cu" signal)
		(9 "F.Adhes" user "F.Adhesive")
		(11 "B.Adhes" user "B.Adhesive")
		(13 "F.Paste" user)
		(15 "B.Paste" user)
		(5 "F.SilkS" user "F.Silkscreen")
		(7 "B.SilkS" user "B.Silkscreen")
		(1 "F.Mask" user)
		(3 "B.Mask" user)
		(17 "Dwgs.User" user "User.Drawings")
		(19 "Cmts.User" user "User.Comments")
		(21 "Eco1.User" user "User.Eco1")
		(23 "Eco2.User" user "User.Eco2")
		(25 "Edge.Cuts" user)
		(27 "Margin" user)
		(31 "F.CrtYd" user "F.Courtyard")
		(29 "B.CrtYd" user "B.Courtyard")
		(35 "F.Fab" user)
		(33 "B.Fab" user)
	)
	(footprint "antmicro-footprints:SFF-TA-1002-4C+"
		(layer "F.Cu")
		(at 104.89 177.355)
		(property "Reference" "J9"
			(at -29.6 3.3 0)
			(layer "F.SilkS")
			(hide yes)
			(effects
				(font
					(size 0.7 0.7)
					(thickness 0.15)
				)
				(justify left bottom)
			)
		)
		(property "Value" "SFF-TA-1002-4C+"
			(at 0 4.1 0)
			(layer "F.Fab")
			(effects
				(font
					(size 0.7 0.7)
					(thickness 0.15)
				)
				(justify left bottom)
			)
		)
		(property "Datasheet" "https://cdn.amphenol-icc.com/media/wysiwyg/files/documentation/sme005.pdf?__cf_chl_jschl_tk__=4604d1306574a1ee474ea914090d3e0c57e266a6-1606907014-0-AbkYBTCTl__kMBcY3BDmgKpfUy32FqitwN2Lniuy8W-uyv2Ev04Q-Q5Mr7srIz_Wnur0_9chB4CRbxKSYcEh7IvAJYsUgJ0PWIS5YdRqqHg567uaZciEX2hQP4ss5l6M4XdNrxEjJppHvyRV3ku89t-VmUSzhgCb8oJlyHpTxST4dEmKZNXfM53TM0tmGirdVbCRt1Byrx5pkz_uMvNABIOj7B2-eDGK52J3DWRD76zEyjdxY7Iz11gPiOY5i_QGIR3uOwkR5LBPNXe8zGqAf8--AKa7RqDbIriQRt90_32C4zIuHqbGa05BXS135E65ov80PbVcb4eSiutCqcJUAacUwu3eVnXVeIumfihJxuP8Rv7_n6saeG_2IuQpEiskzovLGKZM3667Y-rm-AL1NRXTamtvBxqTk0vyMvZ60FgJ"
			(at 0 0 0)
			(layer "F.Fab")
			(hide yes)
			(effects
				(font
					(size 1.27 1.27)
					(thickness 0.15)
				)
			)
		)
		(property "Description" "PCB EDGE PCI connector"
			(at 0 0 0)
			(layer "F.Fab")
			(hide yes)
			(effects
				(font
					(size 1.27 1.27)
					(thickness 0.15)
				)
			)
		)
		(property "Author" "Antmicro"
			(at 0 0 0)
			(layer "F.Fab")
			(hide yes)
			(effects
				(font
					(size 1 1)
					(thickness 0.15)
				)
			)
		)
		(property "License" "Apache-2.0"
			(at 0 0 0)
			(layer "F.Fab")
			(hide yes)
			(effects
				(font
					(size 1 1)
					(thickness 0.15)
				)
			)
		)
		(property "MPN" ""
			(at 0 0 0)
			(layer "F.Fab")
			(hide yes)
			(effects
				(font
					(size 1 1)
					(thickness 0.15)
				)
			)
		)
		(property "Manufacturer" ""
			(at 0 0 0)
			(layer "F.Fab")
			(hide yes)
			(effects
				(font
					(size 1 1)
					(thickness 0.15)
				)
			)
		)
		(property "DNP" ""
			(at 0 0 0)
			(unlocked yes)
			(layer "F.Fab")
			(hide yes)
			(effects
				(font
					(size 1 1)
					(thickness 0.15)
				)
			)
		)
		(sheetname "/Edge connector/")
		(sheetfile "edge-connector.kicad_sch")
		(attr exclude_from_pos_files exclude_from_bom allow_missing_courtyard)
		(pad "A1" smd rect
			(at -18.205 -0.2)
			(size 0.38 1.72)
			(layers "B.Cu" "B.Mask")
			(net 31 "I2C[0]_SCL")
			(pinfunction "A1")
			(pintype "passive")
		)
		(pad "A2" smd rect
			(at -17.6 -0.2)
			(size 0.38 1.72)
			(layers "B.Cu" "B.Mask")
			(net 32 "I2C[0]_SDA")
			(pinfunction "A2")
			(pintype "passive")
		)
		(pad "A3" smd rect
			(at -17 -0.2)
			(size 0.38 1.72)
			(layers "B.Cu" "B.Mask")
			(net 22 "I2C[1]_SCL")
			(pinfunction "A3")
			(pintype "passive")
		)
		(pad "A4" smd rect
			(at -16.4 -0.2)
			(size 0.38 1.72)
			(layers "B.Cu" "B.Mask")
			(net 23 "I2C[1]_SDA")
			(pinfunction "A4")
			(pintype "passive")
		)
		(pad "A5" smd rect
			(at -15.8 -0.2)
			(size 0.38 1.72)
			(layers "B.Cu" "B.Mask")
			(net 26 "I2C[2]_SCL")
			(pinfunction "A5")
			(pintype "passive")
		)
		(pad "A6" smd rect
			(at -15.2 -0.2)
			(size 0.38 1.72)
			(layers "B.Cu" "B.Mask")
			(net 25 "I2C[2]_SDA")
			(pinfunction "A6")
			(pintype "passive")
		)
		(pad "A7" smd rect
			(at -14.6 -0.2)
			(size 0.38 1.72)
			(layers "B.Cu" "B.Mask")
			(net 19 "I2C[3]_SCL")
			(pinfunction "A7")
			(pintype "passive")
		)
		(pad "A8" smd rect
			(at -14 -0.2)
			(size 0.38 1.72)
			(layers "B.Cu" "B.Mask")
			(net 21 "I2C[3]_SDA")
			(pinfunction "A8")
			(pintype "passive")
		)
		(pad "A9" smd rect
			(at -13.4 -0.2)
			(size 0.38 1.72)
			(layers "B.Cu" "B.Mask")
			(net 30 "I2C[4]_SCL")
			(pinfunction "A9")
			(pintype "passive")
		)
		(pad "A10" smd rect
			(at -12.8 -0.2)
			(size 0.38 1.72)
			(layers "B.Cu" "B.Mask")
			(net 27 "I2C[4]_SDA")
			(pinfunction "A10")
			(pintype "passive")
		)
		(pad "A11" smd rect
			(at -12.2 0)
			(size 0.38 2.12)
			(layers "B.Cu" "B.Mask")
			(net 18 "I2C[5]_SCL")
			(pinfunction "A11")
			(pintype "passive")
		)
		(pad "A12" smd rect
			(at -11.6 -0.2)
			(size 0.38 1.72)
			(layers "B.Cu" "B.Mask")
			(net 17 "I2C[5]_SDA")
			(pinfunction "A12")
			(pintype "passive")
		)
		(pad "A13" smd rect
			(at -11 -0.2)
			(size 0.38 1.72)
			(layers "B.Cu" "B.Mask")
			(net 1 "GND")
			(pinfunction "A13")
			(pintype "passive")
		)
		(pad "A14" smd rect
			(at -10.4 0)
			(size 0.38 2.12)
			(layers "B.Cu" "B.Mask")
			(net 379 "PCIE_BMC_CLK_100_P")
			(pinfunction "A14")
			(pintype "passive")
		)
		(pad "A15" smd rect
			(at -9.8 -0.2)
			(size 0.38 1.72)
			(layers "B.Cu" "B.Mask")
			(net 380 "PCIE_BMC_CLK_100_N")
			(pinfunction "A15")
			(pintype "passive")
		)
		(pad "A16" smd rect
			(at -9.2 -0.2)
			(size 0.38 1.72)
			(layers "B.Cu" "B.Mask")
			(net 1 "GND")
			(pinfunction "A16")
			(pintype "passive")
		)
		(pad "A17" smd rect
			(at -8.6 0)
			(size 0.38 2.12)
			(layers "B.Cu" "B.Mask")
			(net 378 "PCIE_BMC_TX_P")
			(pinfunction "A17")
			(pintype "passive")
		)
		(pad "A18" smd rect
			(at -8 -0.2)
			(size 0.38 1.72)
			(layers "B.Cu" "B.Mask")
			(net 377 "PCIE_BMC_TX_N")
			(pinfunction "A18")
			(pintype "passive")
		)
		(pad "A19" smd rect
			(at -7.4 -0.2)
			(size 0.38 1.72)
			(layers "B.Cu" "B.Mask")
			(net 1 "GND")
			(pinfunction "A19")
			(pintype "passive")
		)
		(pad "A20" smd rect
			(at -6.8 0)
			(size 0.38 2.12)
			(layers "B.Cu" "B.Mask")
			(net 381 "PCIE_BMC_RX_P")
			(pinfunction "A20")
			(pintype "passive")
		)
		(pad "A21" smd rect
			(at -6.2 -0.2)
			(size 0.38 1.72)
			(layers "B.Cu" "B.Mask")
			(net 382 "PCIE_BMC_RX_N")
			(pinfunction "A21")
			(pintype "passive")
		)
		(pad "A22" smd rect
			(at -5.6 -0.2)
			(size 0.38 1.72)
			(layers "B.Cu" "B.Mask")
			(net 1 "GND")
			(pinfunction "A22")
			(pintype "passive")
		)
		(pad "A23" smd rect
			(at -5 -0.2)
			(size 0.38 1.72)
			(layers "B.Cu" "B.Mask")
			(net 28 "I2C[6]_SCL")
			(pinfunction "A23")
			(pintype "passive")
		)
		(pad "A24" smd rect
			(at -4.4 -0.2)
			(size 0.38 1.72)
			(layers "B.Cu" "B.Mask")
			(net 29 "I2C[6]_SDA")
			(pinfunction "A24")
			(pintype "passive")
		)
		(pad "A25" smd rect
			(at -3.8 -0.2)
			(size 0.38 1.72)
			(layers "B.Cu" "B.Mask")
			(net 20 "I2C[7]_SCL")
			(pinfunction "A25")
			(pintype "passive")
		)
		(pad "A26" smd rect
			(at -3.2 -0.2)
			(size 0.38 1.72)
			(layers "B.Cu" "B.Mask")
			(net 24 "I2C[7]_SDA")
			(pinfunction "A26")
			(pintype "passive")
		)
		(pad "A27" smd rect
			(at -2.6 -0.2)
			(size 0.38 1.72)
			(layers "B.Cu" "B.Mask")
			(net 45 "I2C[8]_SCL")
			(pinfunction "A27")
			(pintype "passive")
		)
		(pad "A28" smd rect
			(at -2 -0.2)
			(size 0.38 1.72)
			(layers "B.Cu" "B.Mask")
			(net 46 "I2C[8]_SDA")
			(pinfunction "A28")
			(pintype "passive")
		)
		(pad "A29" smd rect
			(at 2.01 -0.2)
			(size 0.38 1.72)
			(layers "B.Cu" "B.Mask")
			(net 37 "I2C[9]_SCL")
			(pinfunction "A29")
			(pintype "passive")
		)
		(pad "A30" smd rect
			(at 2.6 -0.2)
			(size 0.38 1.72)
			(layers "B.Cu" "B.Mask")
			(net 38 "I2C[9]_SDA")
			(pinfunction "A30")
			(pintype "passive")
		)
		(pad "A31" smd rect
			(at 3.2 -0.2)
			(size 0.38 1.72)
			(layers "B.Cu" "B.Mask")
			(net 42 "I2C[10]_SCL")
			(pinfunction "A31")
			(pintype "passive")
		)
		(pad "A32" smd rect
			(at 3.8 -0.2)
			(size 0.38 1.72)
			(layers "B.Cu" "B.Mask")
			(net 41 "I2C[10]_SDA")
			(pinfunction "A32")
			(pintype "passive")
		)
		(pad "A33" smd rect
			(at 4.4 0)
			(size 0.38 2.12)
			(layers "B.Cu" "B.Mask")
			(net 1 "GND")
			(pinfunction "A33")
			(pintype "passive")
		)
		(pad "A34" smd rect
			(at 5 -0.2)
			(size 0.38 1.72)
			(layers "B.Cu" "B.Mask")
			(net 15 "JTAG_TCK")
			(pinfunction "A34")
			(pintype "passive")
		)
		(pad "A35" smd rect
			(at 5.6 -0.2)
			(size 0.38 1.72)
			(layers "B.Cu" "B.Mask")
			(net 16 "JTAG_TMS")
			(pinfunction "A35")
			(pintype "passive")
		)
		(pad "A36" smd rect
			(at 6.2 -0.2)
			(size 0.38 1.72)
			(layers "B.Cu" "B.Mask")
			(net 13 "JTAG_TDI")
			(pinfunction "A36")
			(pintype "passive")
		)
		(pad "A37" smd rect
			(at 6.8 -0.2)
			(size 0.38 1.72)
			(layers "B.Cu" "B.Mask")
			(net 14 "JTAG_TDO")
			(pinfunction "A37")
			(pintype "passive")
		)
		(pad "A38" smd rect
			(at 7.4 -0.2)
			(size 0.38 1.72)
			(layers "B.Cu" "B.Mask")
			(net 34 "I2C[11]_SCL")
			(pinfunction "A38")
			(pintype "passive")
		)
		(pad "A39" smd rect
			(at 8 -0.2)
			(size 0.38 1.72)
			(layers "B.Cu" "B.Mask")
			(net 36 "I2C[11]_SDA")
			(pinfunction "A39")
			(pintype "passive")
		)
		(pad "A40" smd rect
			(at 8.6 -0.2)
			(size 0.38 1.72)
			(layers "B.Cu" "B.Mask")
			(net 44 "I2C[12]_SCL")
			(pinfunction "A40")
			(pintype "passive")
		)
		(pad "A41" smd rect
			(at 9.2 -0.2)
			(size 0.38 1.72)
			(layers "B.Cu" "B.Mask")
			(net 43 "I2C[12]_SDA")
			(pinfunction "A41")
			(pintype "passive")
		)
		(pad "A42" smd rect
			(at 9.8 0)
			(size 0.38 2.12)
			(layers "B.Cu" "B.Mask")
			(net 1 "GND")
			(pinfunction "A42")
			(pintype "passive")
		)
		(pad "A43" smd rect
			(at 14.715 -0.2)
			(size 0.38 1.72)
			(layers "B.Cu" "B.Mask")
			(net 258 "/Edge connector/HPM_FW_RECOVERY")
			(pinfunction "A43")
			(pintype "passive")
		)
		(pad "A44" smd rect
			(at 15.3 -0.2)
			(size 0.38 1.72)
			(layers "B.Cu" "B.Mask")
			(net 257 "/Edge connector/HPM_STBY_RDY")
			(pinfunction "A44")
			(pintype "passive")
		)
		(pad "A45" smd rect
			(at 15.9 -0.2)
			(size 0.38 1.72)
			(layers "B.Cu" "B.Mask")
			(net 256 "/Edge connector/HPM_STBY_EN")
			(pinfunction "A45")
			(pintype "passive")
		)
		(pad "A46" smd rect
			(at 16.5 -0.2)
			(size 0.38 1.72)
			(layers "B.Cu" "B.Mask")
			(net 255 "/Edge connector/HPM_STBY_RST_N")
			(pinfunction "A46")
			(pintype "passive")
		)
		(pad "A47" smd rect
			(at 17.1 -0.2)
			(size 0.38 1.72)
			(layers "B.Cu" "B.Mask")
			(net 254 "/Edge connector/SYS_PWRBTN_N")
			(pinfunction "A47")
			(pintype "passive")
		)
		(pad "A48" smd rect
			(at 17.7 -0.2)
			(size 0.38 1.72)
			(layers "B.Cu" "B.Mask")
			(net 253 "/Edge connector/SYS_PWROK")
			(pinfunction "A48")
			(pintype "passive")
		)
		(pad "A49" smd rect
			(at 18.3 -0.2)
			(size 0.38 1.72)
			(layers "B.Cu" "B.Mask")
			(net 252 "/Edge connector/DBP_PREQ_N")
			(pinfunction "A49")
			(pintype "passive")
		)
		(pad "A50" smd rect
			(at 18.9 -0.2)
			(size 0.38 1.72)
			(layers "B.Cu" "B.Mask")
			(net 251 "/Edge connector/DBP_PRDY_N")
			(pinfunction "A50")
			(pintype "passive")
		)
		(pad "A51" smd rect
			(at 19.5 -0.2)
			(size 0.38 1.72)
			(layers "B.Cu" "B.Mask")
			(net 248 "/Edge connector/RST_PLTRST_BUF_N")
			(pinfunction "A51")
			(pintype "passive")
		)
		(pad "A52" smd rect
			(at 20.1 -0.2)
			(size 0.38 1.72)
			(layers "B.Cu" "B.Mask")
			(net 249 "/Edge connector/SPARE1")
			(pinfunction "A52")
			(pintype "passive")
		)
		(pad "A53" smd rect
			(at 20.7 -0.2)
			(size 0.38 1.72)
			(layers "B.Cu" "B.Mask")
			(net 250 "/Edge connector/RoT_CPU_RST_N")
			(pinfunction "A53")
			(pintype "passive")
		)
		(pad "A54" smd rect
			(at 21.3 -0.2)
			(size 0.38 1.72)
			(layers "B.Cu" "B.Mask")
			(net 247 "/Edge connector/CHASI#")
			(pinfunction "A54")
			(pintype "passive")
		)
		(pad "A55" smd rect
			(at 21.9 -0.2)
			(size 0.38 1.72)
			(layers "B.Cu" "B.Mask")
			(net 246 "/Edge connector/SPARE0")
			(pinfunction "A55")
			(pintype "passive")
		)
		(pad "A56" smd rect
			(at 22.5 -0.2)
			(size 0.38 1.72)
			(layers "B.Cu" "B.Mask")
			(net 245 "/Edge connector/IRQ_N")
			(pinfunction "A56")
			(pintype "passive")
		)
		(pad "A57" smd rect
			(at 23.1 -0.2)
			(size 0.38 1.72)
			(layers "B.Cu" "B.Mask")
			(net 118 "PRSNT1_N")
			(pinfunction "A57")
			(pintype "passive")
		)
		(pad "A58" smd rect
			(at 23.7 0)
			(size 0.38 2.12)
			(layers "B.Cu" "B.Mask")
			(net 1 "GND")
			(pinfunction "A58")
			(pintype "passive")
		)
		(pad "A59" smd rect
			(at 24.3 -0.2)
			(size 0.38 1.72)
			(layers "B.Cu" "B.Mask")
			(net 361 "PCIE_HPM_RX[0]_P")
			(pinfunction "A59")
			(pintype "passive")
		)
		(pad "A60" smd rect
			(at 24.9 -0.2)
			(size 0.38 1.72)
			(layers "B.Cu" "B.Mask")
			(net 362 "PCIE_HPM_RX[0]_N")
			(pinfunction "A60")
			(pintype "passive")
		)
		(pad "A61" smd rect
			(at 25.5 0)
			(size 0.38 2.12)
			(layers "B.Cu" "B.Mask")
			(net 1 "GND")
			(pinfunction "A61")
			(pintype "passive")
		)
		(pad "A62" smd rect
			(at 26.1 -0.2)
			(size 0.38 1.72)
			(layers "B.Cu" "B.Mask")
			(net 363 "PCIE_HPM_RX[1]_P")
			(pinfunction "A62")
			(pintype "passive")
		)
		(pad "A63" smd rect
			(at 26.7 -0.2)
			(size 0.38 1.72)
			(layers "B.Cu" "B.Mask")
			(net 364 "PCIE_HPM_RX[1]_N")
			(pinfunction "A63")
			(pintype "passive")
		)
		(pad "A64" smd rect
			(at 27.3 0)
			(size 0.38 2.12)
			(layers "B.Cu" "B.Mask")
			(net 1 "GND")
			(pinfunction "A64")
			(pintype "passive")
		)
		(pad "A65" smd rect
			(at 27.9 -0.2)
			(size 0.38 1.72)
			(layers "B.Cu" "B.Mask")
			(net 365 "PCIE_HPM_RX[2]_P")
			(pinfunction "A65")
			(pintype "passive")
		)
		(pad "A66" smd rect
			(at 28.5 -0.2)
			(size 0.38 1.72)
			(layers "B.Cu" "B.Mask")
			(net 366 "PCIE_HPM_RX[2]_N")
			(pinfunction "A66")
			(pintype "passive")
		)
		(pad "A67" smd rect
			(at 29.1 0)
			(size 0.38 2.12)
			(layers "B.Cu" "B.Mask")
			(net 1 "GND")
			(pinfunction "A67")
			(pintype "passive")
		)
		(pad "A68" smd rect
			(at 29.7 -0.2)
			(size 0.38 1.72)
			(layers "B.Cu" "B.Mask")
			(net 367 "PCIE_HPM_RX[3]_P")
			(pinfunction "A68")
			(pintype "passive")
		)
		(pad "A69" smd rect
			(at 30.3 -0.2)
			(size 0.38 1.72)
			(layers "B.Cu" "B.Mask")
			(net 368 "PCIE_HPM_RX[3]_N")
			(pinfunction "A69")
			(pintype "passive")
		)
		(pad "A70" smd rect
			(at 30.9 0)
			(size 0.38 2.12)
			(layers "B.Cu" "B.Mask")
			(net 1 "GND")
			(pinfunction "A70")
			(pintype "passive")
		)
		(pad "B1" smd rect
			(at -18.205 -0.2)
			(size 0.38 1.72)
			(layers "F.Cu" "F.Mask")
			(net 584 "ESPI_CLK_1V8")
			(pinfunction "B1")
			(pintype "passive")
		)
		(pad "B2" smd rect
			(at -17.6 -0.2)
			(size 0.38 1.72)
			(layers "F.Cu" "F.Mask")
			(net 583 "ESPI_CS0_N_1V8")
			(pinfunction "B2")
			(pintype "passive")
		)
		(pad "B3" smd rect
			(at -17 -0.2)
			(size 0.38 1.72)
			(layers "F.Cu" "F.Mask")
			(net 582 "ESPI_ALERT_N_1V8")
			(pinfunction "B3")
			(pintype "passive")
		)
		(pad "B4" smd rect
			(at -16.4 -0.2)
			(size 0.38 1.72)
			(layers "F.Cu" "F.Mask")
			(net 581 "ESPI_RESET_N_1V8")
			(pinfunction "B4")
			(pintype "passive")
		)
		(pad "B5" smd rect
			(at -15.8 -0.2)
			(size 0.38 1.72)
			(layers "F.Cu" "F.Mask")
			(net 580 "ESPI_IO0_1V8")
			(pinfunction "B5")
			(pintype "passive")
		)
		(pad "B6" smd rect
			(at -15.2 -0.2)
			(size 0.38 1.72)
			(layers "F.Cu" "F.Mask")
			(net 579 "ESPI_IO1_1V8")
			(pinfunction "B6")
			(pintype "passive")
		)
		(pad "B7" smd rect
			(at -14.6 -0.2)
			(size 0.38 1.72)
			(layers "F.Cu" "F.Mask")
			(net 578 "ESPI_IO2_1V8")
			(pinfunction "B7")
			(pintype "passive")
		)
		(pad "B8" smd rect
			(at -14 -0.2)
			(size 0.38 1.72)
			(layers "F.Cu" "F.Mask")
			(net 577 "ESPI_IO3_1V8")
			(pinfunction "B8")
			(pintype "passive")
		)
		(pad "B9" smd rect
			(at -13.4 -0.2)
			(size 0.38 1.72)
			(layers "F.Cu" "F.Mask")
			(net 576 "ESPI_CS1_N_1V8")
			(pinfunction "B9")
			(pintype "passive")
		)
		(pad "B10" smd rect
			(at -12.8 0)
			(size 0.38 2.12)
			(layers "F.Cu" "F.Mask")
			(net 1 "GND")
			(pinfunction "B10")
			(pintype "passive")
		)
		(pad "B11" smd rect
			(at -12.2 -0.2)
			(size 0.38 1.72)
			(layers "F.Cu" "F.Mask")
			(net 70 "QSPI0_CLK")
			(pinfunction "B11")
			(pintype "passive")
		)
		(pad "B12" smd rect
			(at -11.6 -0.2)
			(size 0.38 1.72)
			(layers "F.Cu" "F.Mask")
			(net 71 "QSPI0_CS0_N")
			(pinfunction "B12")
			(pintype "passive")
		)
		(pad "B13" smd rect
			(at -11 -0.2)
			(size 0.38 1.72)
			(layers "F.Cu" "F.Mask")
			(net 72 "QSPI0_D0")
			(pinfunction "B13")
			(pintype "passive")
		)
		(pad "B14" smd rect
			(at -10.4 -0.2)
			(size 0.38 1.72)
			(layers "F.Cu" "F.Mask")
			(net 73 "QSPI0_D1")
			(pinfunction "B14")
			(pintype "passive")
		)
		(pad "B15" smd rect
			(at -9.8 -0.2)
			(size 0.38 1.72)
			(layers "F.Cu" "F.Mask")
			(net 74 "QSPI0_D2")
			(pinfunction "B15")
			(pintype "passive")
		)
		(pad "B16" smd rect
			(at -9.2 -0.2)
			(size 0.38 1.72)
			(layers "F.Cu" "F.Mask")
			(net 75 "QSPI0_D3")
			(pinfunction "B16")
			(pintype "passive")
		)
		(pad "B17" smd rect
			(at -8.6 0)
			(size 0.38 2.12)
			(layers "F.Cu" "F.Mask")
			(net 1 "GND")
			(pinfunction "B17")
			(pintype "passive")
		)
		(pad "B18" smd rect
			(at -8 -0.2)
			(size 0.38 1.72)
			(layers "F.Cu" "F.Mask")
			(net 76 "NCSI_CLK")
			(pinfunction "B18")
			(pintype "passive")
		)
		(pad "B19" smd rect
			(at -7.4 -0.2)
			(size 0.38 1.72)
			(layers "F.Cu" "F.Mask")
			(net 77 "NCSI_CRS_DV")
			(pinfunction "B19")
			(pintype "passive")
		)
		(pad "B20" smd rect
			(at -6.8 -0.2)
			(size 0.38 1.72)
			(layers "F.Cu" "F.Mask")
			(net 78 "NCSI_TXEN")
			(pinfunction "B20")
			(pintype "passive")
		)
		(pad "B21" smd rect
			(at -6.2 -0.2)
			(size 0.38 1.72)
			(layers "F.Cu" "F.Mask")
			(net 79 "NCSI_TXD0")
			(pinfunction "B21")
			(pintype "passive")
		)
	)
)
